(kicad_pcb
	(version 20260206)
	(generator "pcbnew")
	(generator_version "10.0")
	(general
		(thickness 1.6)
		(legacy_teardrops no)
	)
	(paper "A4")
	(title_block
		(title "dpb — 14545-sa.0730WZS0815.brd")
		(comment 1 "Honey Badger (Wiwynn) / footprints 160-166 of 1066")
	)
	(layers
		(0 "F.Cu" signal "TOP")
		(4 "In1.Cu" signal "L2GND")
		(6 "In2.Cu" signal "L3")
		(8 "In3.Cu" signal "L4VCC")
		(10 "In4.Cu" signal "L5VCC")
		(12 "In5.Cu" signal "L6")
		(14 "In6.Cu" signal "L7GND")
		(2 "B.Cu" signal "BOTTOM")
		(9 "F.Adhes" user "F.Adhesive")
		(11 "B.Adhes" user "B.Adhesive")
		(13 "F.Paste" user "Package Geometry/Pastemask Top")
		(15 "B.Paste" user "Package Geometry/Pastemask Bottom")
		(5 "F.SilkS" user "Ref Des/Silkscreen Top")
		(7 "B.SilkS" user "Ref Des/Silkscreen Bottom")
		(1 "F.Mask" user "Board Geometry/Soldermask Top")
		(3 "B.Mask" user "Board Geometry/Soldermask Bottom")
		(17 "Dwgs.User" user "User.Drawings")
		(19 "Cmts.User" user "User.Comments")
		(21 "Eco1.User" user "User.Eco1")
		(23 "Eco2.User" user "User.Eco2")
		(25 "Edge.Cuts" user "Board Geometry/Outline")
		(27 "Margin" user)
		(31 "F.CrtYd" user "Package Geometry/Place Bound Top")
		(29 "B.CrtYd" user "Package Geometry/Place Bound Bottom")
		(35 "F.Fab" user "Ref Des/Assembly Top")
		(33 "B.Fab" user "Ref Des/Assembly Bottom")
	)
	(footprint ""
		(layer "F.Cu")
		(at 210.609942 -459.000098 180)
		(property "Reference" "U48"
			(at 0 0 180)
			(layer "F.SilkS")
			(hide yes)
			(effects
				(font
					(size 1.27 1.27)
				)
			)
		)
		(property "Value" "TMP75AIDGKR-GP"
			(at -0.1143 -9.1948 180)
			(unlocked yes)
			(layer "F.Fab")
			(hide yes)
			(effects
				(font
					(size 1.016 1.016)
					(thickness 0.1524)
				)
			)
		)
		(property "Device Type" "MSOP8-1H44"
			(at -0.1143 -10.795 180)
			(unlocked yes)
			(layer "F.Fab")
			(hide yes)
			(effects
				(font
					(size 1.016 1.016)
					(thickness 0.1524)
				)
			)
		)
		(duplicate_pad_numbers_are_jumpers no)
		(fp_line
			(start 1.0795 1.016)
			(end 1.0795 -1.016)
			(stroke
				(width 0.1524)
				(type default)
			)
			(layer "F.SilkS")
		)
		(fp_line
			(start 1.0795 -1.016)
			(end -1.9558 -1.016)
			(stroke
				(width 0.1524)
				(type default)
			)
			(layer "F.SilkS")
		)
		(fp_line
			(start -1.4478 -0.0381)
			(end -1.9558 0.4699)
			(stroke
				(width 0.1524)
				(type default)
			)
			(layer "F.SilkS")
		)
		(fp_line
			(start -1.778 1.0922)
			(end -1.778 3.048)
			(stroke
				(width 0.508)
				(type default)
			)
			(layer "F.SilkS")
		)
		(fp_line
			(start -1.9558 1.016)
			(end 1.0795 1.016)
			(stroke
				(width 0.1524)
				(type default)
			)
			(layer "F.SilkS")
		)
		(fp_line
			(start -1.9558 -0.5461)
			(end -1.4478 -0.0381)
			(stroke
				(width 0.1524)
				(type default)
			)
			(layer "F.SilkS")
		)
		(fp_line
			(start -1.9558 -1.016)
			(end -1.9558 1.016)
			(stroke
				(width 0.1524)
				(type default)
			)
			(layer "F.SilkS")
		)
		(fp_poly
			(pts
				(xy -1.1557 -1.016) (xy -1.1557 1.016) (xy 1.1557 1.016) (xy 1.1557 -1.016)
			)
			(stroke
				(width 0)
				(type default)
			)
			(fill yes)
			(layer "F.SilkS")
		)
		(fp_rect
			(start -1.4986 2.4511)
			(end 1.4986 -2.4511)
			(stroke
				(width 0)
				(type default)
			)
			(fill no)
			(layer "F.CrtYd")
		)
		(fp_poly
			(pts
				(xy -2.032 3.302) (xy -2.032 -3.302) (xy 2.032 -3.302) (xy 2.032 -2.1209) (xy 1.4986 -2.1209) (xy 1.4986 -2.4511)
				(xy -1.4986 -2.4511) (xy -1.4986 2.4511) (xy 1.4986 2.4511) (xy 1.4986 -2.1082) (xy 2.032 -2.1082)
				(xy 2.032 3.302)
			)
			(stroke
				(width 0)
				(type default)
			)
			(fill no)
			(layer "F.CrtYd")
		)
		(fp_rect
			(start -2.032 3.302)
			(end 2.032 -3.302)
			(stroke
				(width 0)
				(type default)
			)
			(fill no)
			(layer "F.Fab")
		)
		(pad "1" smd rect
			(at -0.97536 2.05486 180)
			(size 0.3556 1.524)
			(layers "F.Cu" "F.Mask" "F.Paste")
			(net "TMP3_SDA")
		)
		(pad "2" smd rect
			(at -0.32512 2.05486 180)
			(size 0.3556 1.524)
			(layers "F.Cu" "F.Mask" "F.Paste")
			(net "TMP3_SCL")
		)
		(pad "3" smd rect
			(at 0.32512 2.05486 180)
			(size 0.3556 1.524)
			(layers "F.Cu" "F.Mask" "F.Paste")
			(net "I2C_B_TMP3_ALERT")
		)
		(pad "4" smd rect
			(at 0.97536 2.05486 180)
			(size 0.3556 1.524)
			(layers "F.Cu" "F.Mask" "F.Paste")
			(net "GND")
		)
		(pad "5" smd rect
			(at 0.97536 -2.05486 180)
			(size 0.3556 1.524)
			(layers "F.Cu" "F.Mask" "F.Paste")
			(net "I2C_B_TMP3_A2")
		)
		(pad "6" smd rect
			(at 0.32512 -2.05486 180)
			(size 0.3556 1.524)
			(layers "F.Cu" "F.Mask" "F.Paste")
			(net "I2C_B_TMP3_A1")
		)
		(pad "7" smd rect
			(at -0.32512 -2.05486 180)
			(size 0.3556 1.524)
			(layers "F.Cu" "F.Mask" "F.Paste")
			(net "I2C_B_TMP3_A0")
		)
		(pad "8" smd rect
			(at -0.97536 -2.05486 180)
			(size 0.3556 1.524)
			(layers "F.Cu" "F.Mask" "F.Paste")
			(net "P3V3")
		)
	)
	(footprint ""
		(layer "F.Cu")
		(at 221.444058 -349.452184 90)
		(property "Reference" "R117"
			(at 0 0 90)
			(layer "F.SilkS")
			(hide yes)
			(effects
				(font
					(size 1.27 1.27)
				)
			)
		)
		(property "Value" "330R2F-GP"
			(at 0.064008 -3.993896 90)
			(unlocked yes)
			(layer "F.Fab")
			(hide yes)
			(effects
				(font
					(size 1.016 1.016)
					(thickness 0.1524)
				)
			)
		)
		(property "Device Type" "R402H16"
			(at 0.064008 -5.517896 90)
			(unlocked yes)
			(layer "F.Fab")
			(hide yes)
			(effects
				(font
					(size 1.016 1.016)
					(thickness 0.1524)
				)
			)
		)
		(duplicate_pad_numbers_are_jumpers no)
		(fp_line
			(start 0.508 -0.9398)
			(end -0.508 -0.9398)
			(stroke
				(width 0.1524)
				(type default)
			)
			(layer "F.SilkS")
		)
		(fp_line
			(start -0.508 -0.9398)
			(end -0.508 0.9398)
			(stroke
				(width 0.1524)
				(type default)
			)
			(layer "F.SilkS")
		)
		(fp_rect
			(start -0.508 0.9398)
			(end 0.508 -0.9398)
			(stroke
				(width 0)
				(type default)
			)
			(fill no)
			(layer "F.CrtYd")
		)
		(fp_rect
			(start -0.508 0.9398)
			(end 0.508 -0.9398)
			(stroke
				(width 0)
				(type default)
			)
			(fill no)
			(layer "F.Fab")
		)
		(pad "1" smd custom
			(at 0 -0.4445 90)
			(size 0.1397 0.1397)
			(layers "F.Cu" "F.Mask" "F.Paste")
			(net "P3V3_HDD1_LED")
			(options
				(clearance outline)
				(anchor circle)
			)
			(primitives
				(gr_poly
					(pts
						(arc
							(start -0.1778 -0.2794)
							(mid -0.249642 -0.249642)
							(end -0.2794 -0.1778)
						)
						(arc
							(start -0.2794 0.1778)
							(mid -0.249642 0.249642)
							(end -0.1778 0.2794)
						)
						(arc
							(start 0.1778 0.2794)
							(mid 0.249642 0.249642)
							(end 0.2794 0.1778)
						)
						(arc
							(start 0.2794 -0.1778)
							(mid 0.249642 -0.249642)
							(end 0.1778 -0.2794)
						)
					)
					(width 0)
					(fill yes)
				)
			)
		)
		(pad "2" smd custom
			(at 0 0.4445 90)
			(size 0.1397 0.1397)
			(layers "F.Cu" "F.Mask" "F.Paste")
			(net "FLT_HDD1")
			(options
				(clearance outline)
				(anchor circle)
			)
			(primitives
				(gr_poly
					(pts
						(arc
							(start -0.1778 -0.2794)
							(mid -0.249642 -0.249642)
							(end -0.2794 -0.1778)
						)
						(arc
							(start -0.2794 0.1778)
							(mid -0.249642 0.249642)
							(end -0.1778 0.2794)
						)
						(arc
							(start 0.1778 0.2794)
							(mid 0.249642 0.249642)
							(end 0.2794 0.1778)
						)
						(arc
							(start 0.2794 -0.1778)
							(mid 0.249642 -0.249642)
							(end 0.1778 -0.2794)
						)
					)
					(width 0)
					(fill yes)
				)
			)
		)
	)
	(footprint ""
		(layer "F.Cu")
		(at 46.7106 -238.9632)
		(property "Reference" "Q70"
			(at 0 0 0)
			(layer "F.SilkS")
			(hide yes)
			(effects
				(font
					(size 1.27 1.27)
				)
			)
		)
		(property "Value" "2N7002DW-7F-GP"
			(at -2.3622 -8.2042 0)
			(unlocked yes)
			(layer "F.Fab")
			(hide yes)
			(effects
				(font
					(size 1.016 1.016)
					(thickness 0.1524)
				)
			)
		)
		(property "Device Type" "SOT-363H44"
			(at -2.3622 -10.1092 0)
			(unlocked yes)
			(layer "F.Fab")
			(hide yes)
			(effects
				(font
					(size 1.016 1.016)
					(thickness 0.1524)
				)
			)
		)
		(duplicate_pad_numbers_are_jumpers no)
		(fp_line
			(start -1.4478 -1.7018)
			(end -1.4478 1.7018)
			(stroke
				(width 0.1524)
				(type default)
			)
			(layer "F.SilkS")
		)
		(fp_line
			(start -1.4478 1.7018)
			(end 1.4478 1.7018)
			(stroke
				(width 0.1524)
				(type default)
			)
			(layer "F.SilkS")
		)
		(fp_line
			(start -1.27 1.524)
			(end -1.27 0.6604)
			(stroke
				(width 0.4826)
				(type default)
			)
			(layer "F.SilkS")
		)
		(fp_line
			(start 1.4478 -1.7018)
			(end -1.4478 -1.7018)
			(stroke
				(width 0.1524)
				(type default)
			)
			(layer "F.SilkS")
		)
		(fp_line
			(start 1.4478 1.7018)
			(end 1.4478 -1.7018)
			(stroke
				(width 0.1524)
				(type default)
			)
			(layer "F.SilkS")
		)
		(fp_poly
			(pts
				(xy -1.524 -1.778) (xy 1.524 -1.778) (xy 1.524 1.778) (xy -1.524 1.778)
			)
			(stroke
				(width 0)
				(type default)
			)
			(fill no)
			(layer "F.CrtYd")
		)
		(fp_poly
			(pts
				(xy -1.524 -1.778) (xy 1.524 -1.778) (xy 1.524 1.778) (xy -1.524 1.778)
			)
			(stroke
				(width 0)
				(type default)
			)
			(fill no)
			(layer "F.Fab")
		)
		(pad "1" smd rect
			(at -0.65024 0.9398)
			(size 0.4064 1.016)
			(layers "F.Cu" "F.Mask" "F.Paste")
			(net "P3V3_HDD12_LED")
		)
		(pad "2" smd rect
			(at 0 0.9398)
			(size 0.4064 1.016)
			(layers "F.Cu" "F.Mask" "F.Paste")
			(net "HDD12_LED_G")
		)
		(pad "3" smd rect
			(at 0.65024 0.9398)
			(size 0.4064 1.016)
			(layers "F.Cu" "F.Mask" "F.Paste")
			(net "P5VC")
		)
		(pad "4" smd rect
			(at 0.65024 -0.9398)
			(size 0.4064 1.016)
			(layers "F.Cu" "F.Mask" "F.Paste")
			(net "P5VC_HDD12_LED")
		)
		(pad "5" smd rect
			(at 0 -0.9398)
			(size 0.4064 1.016)
			(layers "F.Cu" "F.Mask" "F.Paste")
			(net "HDD12_LED_G")
		)
		(pad "6" smd rect
			(at -0.65024 -0.9398)
			(size 0.4064 1.016)
			(layers "F.Cu" "F.Mask" "F.Paste")
			(net "P3V3")
		)
	)
	(footprint ""
		(layer "F.Cu")
		(at 28.600146 -384.0099)
		(property "Reference" "R318"
			(at 0 0 0)
			(layer "F.SilkS")
			(hide yes)
			(effects
				(font
					(size 1.27 1.27)
				)
			)
		)
		(property "Value" "0R2J-2-GP"
			(at 0.064008 -3.993896 0)
			(unlocked yes)
			(layer "F.Fab")
			(hide yes)
			(effects
				(font
					(size 1.016 1.016)
					(thickness 0.1524)
				)
			)
		)
		(property "Device Type" "R402H16"
			(at 0.064008 -5.517896 0)
			(unlocked yes)
			(layer "F.Fab")
			(hide yes)
			(effects
				(font
					(size 1.016 1.016)
					(thickness 0.1524)
				)
			)
		)
		(duplicate_pad_numbers_are_jumpers no)
		(fp_line
			(start -0.508 -0.9398)
			(end -0.508 0.9398)
			(stroke
				(width 0.1524)
				(type default)
			)
			(layer "F.SilkS")
		)
		(fp_line
			(start 0.508 -0.9398)
			(end -0.508 -0.9398)
			(stroke
				(width 0.1524)
				(type default)
			)
			(layer "F.SilkS")
		)
		(fp_rect
			(start -0.508 0.9398)
			(end 0.508 -0.9398)
			(stroke
				(width 0)
				(type default)
			)
			(fill no)
			(layer "F.CrtYd")
		)
		(fp_rect
			(start -0.508 0.9398)
			(end 0.508 -0.9398)
			(stroke
				(width 0)
				(type default)
			)
			(fill no)
			(layer "F.Fab")
		)
		(pad "1" smd custom
			(at 0 -0.4445)
			(size 0.1397 0.1397)
			(layers "F.Cu" "F.Mask" "F.Paste")
			(net "I2C_B_SCL")
			(options
				(clearance outline)
				(anchor circle)
			)
			(primitives
				(gr_poly
					(pts
						(arc
							(start -0.1778 -0.2794)
							(mid -0.249642 -0.249642)
							(end -0.2794 -0.1778)
						)
						(arc
							(start -0.2794 0.1778)
							(mid -0.249642 0.249642)
							(end -0.1778 0.2794)
						)
						(arc
							(start 0.1778 0.2794)
							(mid 0.249642 0.249642)
							(end 0.2794 0.1778)
						)
						(arc
							(start 0.2794 -0.1778)
							(mid 0.249642 -0.249642)
							(end 0.1778 -0.2794)
						)
					)
					(width 0)
					(fill yes)
				)
			)
		)
		(pad "2" smd custom
			(at 0 0.4445)
			(size 0.1397 0.1397)
			(layers "F.Cu" "F.Mask" "F.Paste")
			(net "TMP1_SCL")
			(options
				(clearance outline)
				(anchor circle)
			)
			(primitives
				(gr_poly
					(pts
						(arc
							(start -0.1778 -0.2794)
							(mid -0.249642 -0.249642)
							(end -0.2794 -0.1778)
						)
						(arc
							(start -0.2794 0.1778)
							(mid -0.249642 0.249642)
							(end -0.1778 0.2794)
						)
						(arc
							(start 0.1778 0.2794)
							(mid 0.249642 0.249642)
							(end 0.2794 0.1778)
						)
						(arc
							(start 0.2794 -0.1778)
							(mid 0.249642 -0.249642)
							(end 0.1778 -0.2794)
						)
					)
					(width 0)
					(fill yes)
				)
			)
		)
	)
	(footprint ""
		(layer "F.Cu")
		(at 9.651746 -501.0277 180)
		(property "Reference" "PC36"
			(at 0 0 180)
			(layer "F.SilkS")
			(hide yes)
			(effects
				(font
					(size 1.27 1.27)
				)
			)
		)
		(property "Value" "SC4D7U25V5KX-GP"
			(at -0.0762 -6.1214 180)
			(unlocked yes)
			(layer "F.Fab")
			(hide yes)
			(effects
				(font
					(size 1.016 1.016)
					(thickness 0.1524)
				)
			)
		)
		(property "Device Type" "C805H54"
			(at -0.0762 -8.1534 180)
			(unlocked yes)
			(layer "F.Fab")
			(hide yes)
			(effects
				(font
					(size 1.016 1.016)
					(thickness 0.1524)
				)
			)
		)
		(duplicate_pad_numbers_are_jumpers no)
		(fp_line
			(start 0.635 0)
			(end -0.635 0)
			(stroke
				(width 0.508)
				(type default)
			)
			(layer "F.SilkS")
		)
		(fp_rect
			(start -0.9652 1.778)
			(end 0.9652 -1.778)
			(stroke
				(width 0)
				(type default)
			)
			(fill no)
			(layer "F.CrtYd")
		)
		(fp_poly
			(pts
				(xy -0.9652 -1.778) (xy 0.9652 -1.778) (xy 0.9652 1.778) (xy -0.9652 1.778)
			)
			(stroke
				(width 0)
				(type default)
			)
			(fill no)
			(layer "F.Fab")
		)
		(pad "1" smd rect
			(at 0 -0.9652 180)
			(size 1.397 1.143)
			(layers "F.Cu" "F.Mask" "F.Paste")
			(net "P5VC_VDD")
		)
		(pad "2" smd rect
			(at 0 0.9652 180)
			(size 1.397 1.143)
			(layers "F.Cu" "F.Mask" "F.Paste")
			(net "GND")
		)
	)
	(footprint ""
		(layer "F.Cu")
		(at 221.360746 -345.3257 -90)
		(property "Reference" "R114"
			(at 0 0 270)
			(layer "F.SilkS")
			(hide yes)
			(effects
				(font
					(size 1.27 1.27)
				)
			)
		)
		(property "Value" "10KR2F-2-GP"
			(at 0.064008 -3.993896 270)
			(unlocked yes)
			(layer "F.Fab")
			(hide yes)
			(effects
				(font
					(size 1.016 1.016)
					(thickness 0.1524)
				)
			)
		)
		(property "Device Type" "R402H16"
			(at 0.064008 -5.517896 270)
			(unlocked yes)
			(layer "F.Fab")
			(hide yes)
			(effects
				(font
					(size 1.016 1.016)
					(thickness 0.1524)
				)
			)
		)
		(duplicate_pad_numbers_are_jumpers no)
		(fp_line
			(start -0.508 -0.9398)
			(end -0.508 0.9398)
			(stroke
				(width 0.1524)
				(type default)
			)
			(layer "F.SilkS")
		)
		(fp_line
			(start 0.508 -0.9398)
			(end -0.508 -0.9398)
			(stroke
				(width 0.1524)
				(type default)
			)
			(layer "F.SilkS")
		)
		(fp_rect
			(start -0.508 0.9398)
			(end 0.508 -0.9398)
			(stroke
				(width 0)
				(type default)
			)
			(fill no)
			(layer "F.CrtYd")
		)
		(fp_rect
			(start -0.508 0.9398)
			(end 0.508 -0.9398)
			(stroke
				(width 0)
				(type default)
			)
			(fill no)
			(layer "F.Fab")
		)
		(pad "1" smd custom
			(at 0 -0.4445 270)
			(size 0.1397 0.1397)
			(layers "F.Cu" "F.Mask" "F.Paste")
			(net "P5VA")
			(options
				(clearance outline)
				(anchor circle)
			)
			(primitives
				(gr_poly
					(pts
						(arc
							(start -0.1778 -0.2794)
							(mid -0.249642 -0.249642)
							(end -0.2794 -0.1778)
						)
						(arc
							(start -0.2794 0.1778)
							(mid -0.249642 0.249642)
							(end -0.1778 0.2794)
						)
						(arc
							(start 0.1778 0.2794)
							(mid 0.249642 0.249642)
							(end 0.2794 0.1778)
						)
						(arc
							(start 0.2794 -0.1778)
							(mid 0.249642 -0.249642)
							(end 0.1778 -0.2794)
						)
					)
					(width 0)
					(fill yes)
				)
			)
		)
		(pad "2" smd custom
			(at 0 0.4445 270)
			(size 0.1397 0.1397)
			(layers "F.Cu" "F.Mask" "F.Paste")
			(net "DRIVE_ACT_1")
			(options
				(clearance outline)
				(anchor circle)
			)
			(primitives
				(gr_poly
					(pts
						(arc
							(start -0.1778 -0.2794)
							(mid -0.249642 -0.249642)
							(end -0.2794 -0.1778)
						)
						(arc
							(start -0.2794 0.1778)
							(mid -0.249642 0.249642)
							(end -0.1778 0.2794)
						)
						(arc
							(start 0.1778 0.2794)
							(mid 0.249642 0.249642)
							(end 0.2794 0.1778)
						)
						(arc
							(start 0.2794 -0.1778)
							(mid 0.249642 -0.249642)
							(end 0.1778 -0.2794)
						)
					)
					(width 0)
					(fill yes)
				)
			)
		)
	)
	(footprint ""
		(layer "F.Cu")
		(at 72.516746 -190.5127)
		(property "Reference" "R453"
			(at 0 0 0)
			(layer "F.SilkS")
			(hide yes)
			(effects
				(font
					(size 1.27 1.27)
				)
			)
		)
		(property "Value" "4K7R2J-2-GP"
			(at 0.064008 -3.993896 0)
			(unlocked yes)
			(layer "F.Fab")
			(hide yes)
			(effects
				(font
					(size 1.016 1.016)
					(thickness 0.1524)
				)
			)
		)
		(property "Device Type" "R402H16"
			(at 0.064008 -5.517896 0)
			(unlocked yes)
			(layer "F.Fab")
			(hide yes)
			(effects
				(font
					(size 1.016 1.016)
					(thickness 0.1524)
				)
			)
		)
		(duplicate_pad_numbers_are_jumpers no)
		(fp_line
			(start -0.508 -0.9398)
			(end -0.508 0.9398)
			(stroke
				(width 0.1524)
				(type default)
			)
			(layer "F.SilkS")
		)
		(fp_line
			(start 0.508 -0.9398)
			(end -0.508 -0.9398)
			(stroke
				(width 0.1524)
				(type default)
			)
			(layer "F.SilkS")
		)
		(fp_rect
			(start -0.508 0.9398)
			(end 0.508 -0.9398)
			(stroke
				(width 0)
				(type default)
			)
			(fill no)
			(layer "F.CrtYd")
		)
		(fp_rect
			(start -0.508 0.9398)
			(end 0.508 -0.9398)
			(stroke
				(width 0)
				(type default)
			)
			(fill no)
			(layer "F.Fab")
		)
		(pad "1" smd custom
			(at 0 -0.4445)
			(size 0.1397 0.1397)
			(layers "F.Cu" "F.Mask" "F.Paste")
			(net "P3V3")
			(options
				(clearance outline)
				(anchor circle)
			)
			(primitives
				(gr_poly
					(pts
						(arc
							(start -0.1778 -0.2794)
							(mid -0.249642 -0.249642)
							(end -0.2794 -0.1778)
						)
						(arc
							(start -0.2794 0.1778)
							(mid -0.249642 0.249642)
							(end -0.1778 0.2794)
						)
						(arc
							(start 0.1778 0.2794)
							(mid 0.249642 0.249642)
							(end 0.2794 0.1778)
						)
						(arc
							(start 0.2794 -0.1778)
							(mid 0.249642 -0.249642)
							(end 0.1778 -0.2794)
						)
					)
					(width 0)
					(fill yes)
				)
			)
		)
		(pad "2" smd custom
			(at 0 0.4445)
			(size 0.1397 0.1397)
			(layers "F.Cu" "F.Mask" "F.Paste")
			(net "SAS2X28_B_HDD8_FLT")
			(options
				(clearance outline)
				(anchor circle)
			)
			(primitives
				(gr_poly
					(pts
						(arc
							(start -0.1778 -0.2794)
							(mid -0.249642 -0.249642)
							(end -0.2794 -0.1778)
						)
						(arc
							(start -0.2794 0.1778)
							(mid -0.249642 0.249642)
							(end -0.1778 0.2794)
						)
						(arc
							(start 0.1778 0.2794)
							(mid 0.249642 0.249642)
							(end 0.2794 0.1778)
						)
						(arc
							(start 0.2794 -0.1778)
							(mid 0.249642 -0.249642)
							(end 0.1778 -0.2794)
						)
					)
					(width 0)
					(fill yes)
				)
			)
		)
	)
)
